(kicad_pcb
	(version 20260206)
	(generator "pcbnew")
	(generator_version "10.0")
	(general
		(thickness 1.6)
		(legacy_teardrops no)
	)
	(paper "A4")
	(title_block
		(title "Wiwynn_Tioga_Pass_MB.brd")
		(comment 1 "Tioga Pass / footprints 2234-2240 of 4770")
	)
	(layers
		(0 "F.Cu" signal "TOP")
		(4 "In1.Cu" signal "L2GND")
		(6 "In2.Cu" signal "L3")
		(8 "In3.Cu" signal "L4GND")
		(10 "In4.Cu" signal "L5")
		(12 "In5.Cu" signal "L6GND")
		(14 "In6.Cu" signal "L7VCC")
		(16 "In7.Cu" signal "L8VCC")
		(18 "In8.Cu" signal "L9GND")
		(20 "In9.Cu" signal "L10")
		(22 "In10.Cu" signal "L11GND")
		(24 "In11.Cu" signal "L12")
		(26 "In12.Cu" signal "L13GND")
		(2 "B.Cu" signal "BOTTOM")
		(9 "F.Adhes" user "F.Adhesive")
		(11 "B.Adhes" user "B.Adhesive")
		(13 "F.Paste" user "Package Geometry/Pastemask Top")
		(15 "B.Paste" user "Package Geometry/Pastemask Bottom")
		(5 "F.SilkS" user "Ref Des/Silkscreen Top")
		(7 "B.SilkS" user "Ref Des/Silkscreen Bottom")
		(1 "F.Mask" user "Board Geometry/Soldermask Top")
		(3 "B.Mask" user "Board Geometry/Soldermask Bottom")
		(17 "Dwgs.User" user "User.Drawings")
		(19 "Cmts.User" user "User.Comments")
		(21 "Eco1.User" user "User.Eco1")
		(23 "Eco2.User" user "User.Eco2")
		(25 "Edge.Cuts" user "Board Geometry/Outline")
		(27 "Margin" user)
		(31 "F.CrtYd" user "Package Geometry/Place Bound Top")
		(29 "B.CrtYd" user "Package Geometry/Place Bound Bottom")
		(35 "F.Fab" user "Ref Des/Assembly Top")
		(33 "B.Fab" user "Ref Des/Assembly Bottom")
	)
	(footprint ""
		(layer "F.Cu")
		(at 406.516078 -121.083832 90)
		(property "Reference" "R1W19"
			(at -0.8382 -0.67818 90)
			(unlocked yes)
			(layer "F.SilkS")
			(effects
				(font
					(size 0.4064 0.254)
					(thickness 0.1524)
				)
				(justify left)
			)
		)
		(property "Value" ""
			(at 0 0 90)
			(layer "F.Fab")
			(effects
				(font
					(size 1.27 1.27)
				)
			)
		)
		(duplicate_pad_numbers_are_jumpers no)
		(fp_poly
			(pts
				(xy -0.2794 -0.1016) (xy 0.2794 -0.1016) (xy 0.2794 0.9906) (xy -0.2794 0.9906)
			)
			(stroke
				(width 0)
				(type default)
			)
			(fill no)
			(layer "F.CrtYd")
		)
		(fp_line
			(start 0.2794 -0.1016)
			(end -0.2794 -0.1016)
			(stroke
				(width 0.1)
				(type default)
			)
			(layer "F.Fab")
		)
		(fp_line
			(start -0.2794 -0.1016)
			(end -0.2794 0.9906)
			(stroke
				(width 0.1)
				(type default)
			)
			(layer "F.Fab")
		)
		(fp_line
			(start 0.2794 0.9906)
			(end 0.2794 -0.1016)
			(stroke
				(width 0.1)
				(type default)
			)
			(layer "F.Fab")
		)
		(fp_line
			(start -0.2794 0.9906)
			(end 0.2794 0.9906)
			(stroke
				(width 0.1)
				(type default)
			)
			(layer "F.Fab")
		)
		(pad "1" smd rect
			(at 0 0 90)
			(size 0.508 0.508)
			(layers "F.Cu" "F.Mask" "F.Paste")
			(net "USB2_P02_DN_R")
		)
		(pad "2" smd rect
			(at 0 0.889 90)
			(size 0.508 0.508)
			(layers "F.Cu" "F.Mask" "F.Paste")
			(net "USB2_P02_DN")
		)
		(zone
			(layer "F.Cu")
			(hatch none 0.5)
			(connect_pads
				(clearance 0)
			)
			(min_thickness 0.25)
			(keepout
				(tracks allowed)
				(vias not_allowed)
				(pads allowed)
				(copperpour not_allowed)
				(footprints allowed)
			)
			(placement
				(enabled no)
				(sheetname "")
			)
			(fill
				(thermal_gap 0.5)
				(thermal_bridge_width 0.5)
				(island_removal_mode 0)
			)
			(polygon
				(pts
					(xy 406.770078 -120.829832) (xy 406.770078 -121.337832) (xy 407.151078 -121.337832) (xy 407.151078 -120.829832)
				)
			)
		)
		(zone
			(layer "F.Cu")
			(hatch none 0.5)
			(connect_pads
				(clearance 0)
			)
			(min_thickness 0.25)
			(keepout
				(tracks not_allowed)
				(vias allowed)
				(pads allowed)
				(copperpour not_allowed)
				(footprints allowed)
			)
			(placement
				(enabled no)
				(sheetname "")
			)
			(fill
				(thermal_gap 0.5)
				(thermal_bridge_width 0.5)
				(island_removal_mode 0)
			)
			(polygon
				(pts
					(xy 407.151078 -120.829832) (xy 407.151078 -121.337832) (xy 406.770078 -121.337832) (xy 406.770078 -120.829832)
				)
			)
		)
	)
	(footprint ""
		(layer "F.Cu")
		(at 14.986 -82.169 -90)
		(property "Reference" "R1D18"
			(at 0 0 270)
			(layer "F.SilkS")
			(hide yes)
			(effects
				(font
					(size 1.27 1.27)
				)
			)
		)
		(property "Value" ""
			(at 0 0 270)
			(layer "F.Fab")
			(effects
				(font
					(size 1.27 1.27)
				)
			)
		)
		(duplicate_pad_numbers_are_jumpers no)
		(fp_poly
			(pts
				(xy -0.2794 -0.1016) (xy 0.2794 -0.1016) (xy 0.2794 0.9906) (xy -0.2794 0.9906)
			)
			(stroke
				(width 0)
				(type default)
			)
			(fill no)
			(layer "F.CrtYd")
		)
		(fp_line
			(start -0.2794 0.9906)
			(end 0.2794 0.9906)
			(stroke
				(width 0.1)
				(type default)
			)
			(layer "F.Fab")
		)
		(fp_line
			(start 0.2794 0.9906)
			(end 0.2794 -0.1016)
			(stroke
				(width 0.1)
				(type default)
			)
			(layer "F.Fab")
		)
		(fp_line
			(start -0.2794 -0.1016)
			(end -0.2794 0.9906)
			(stroke
				(width 0.1)
				(type default)
			)
			(layer "F.Fab")
		)
		(fp_line
			(start 0.2794 -0.1016)
			(end -0.2794 -0.1016)
			(stroke
				(width 0.1)
				(type default)
			)
			(layer "F.Fab")
		)
		(pad "1" smd rect
			(at 0 0 270)
			(size 0.508 0.508)
			(layers "F.Cu" "F.Mask" "F.Paste")
			(net "A_HSC_HIGH_EN")
		)
		(pad "2" smd rect
			(at 0 0.889 270)
			(size 0.508 0.508)
			(layers "F.Cu" "F.Mask" "F.Paste")
			(net "AGND_HSC")
		)
		(zone
			(layer "F.Cu")
			(hatch none 0.5)
			(connect_pads
				(clearance 0)
			)
			(min_thickness 0.25)
			(keepout
				(tracks not_allowed)
				(vias allowed)
				(pads allowed)
				(copperpour not_allowed)
				(footprints allowed)
			)
			(placement
				(enabled no)
				(sheetname "")
			)
			(fill
				(thermal_gap 0.5)
				(thermal_bridge_width 0.5)
				(island_removal_mode 0)
			)
			(polygon
				(pts
					(xy 14.351 -82.423) (xy 14.351 -81.915) (xy 14.732 -81.915) (xy 14.732 -82.423)
				)
			)
		)
		(zone
			(layer "F.Cu")
			(hatch none 0.5)
			(connect_pads
				(clearance 0)
			)
			(min_thickness 0.25)
			(keepout
				(tracks allowed)
				(vias not_allowed)
				(pads allowed)
				(copperpour not_allowed)
				(footprints allowed)
			)
			(placement
				(enabled no)
				(sheetname "")
			)
			(fill
				(thermal_gap 0.5)
				(thermal_bridge_width 0.5)
				(island_removal_mode 0)
			)
			(polygon
				(pts
					(xy 14.732 -82.423) (xy 14.732 -81.915) (xy 14.351 -81.915) (xy 14.351 -82.423)
				)
			)
		)
	)
	(footprint ""
		(layer "F.Cu")
		(at 363.87024 -140.88237 180)
		(property "Reference" "C7A28"
			(at 0 0 180)
			(layer "F.SilkS")
			(hide yes)
			(effects
				(font
					(size 1.27 1.27)
				)
			)
		)
		(property "Value" ""
			(at 0 0 180)
			(layer "F.Fab")
			(effects
				(font
					(size 1.27 1.27)
				)
			)
		)
		(duplicate_pad_numbers_are_jumpers no)
		(fp_rect
			(start 0.3048 -0.1016)
			(end -0.3048 0.9906)
			(stroke
				(width 0)
				(type default)
			)
			(fill no)
			(layer "F.CrtYd")
		)
		(fp_line
			(start 0.3048 0.9906)
			(end 0.3048 -0.1016)
			(stroke
				(width 0.1)
				(type default)
			)
			(layer "F.Fab")
		)
		(fp_line
			(start 0.3048 -0.1016)
			(end -0.3048 -0.1016)
			(stroke
				(width 0.1)
				(type default)
			)
			(layer "F.Fab")
		)
		(fp_line
			(start -0.3048 0.9906)
			(end 0.3048 0.9906)
			(stroke
				(width 0.1)
				(type default)
			)
			(layer "F.Fab")
		)
		(fp_line
			(start -0.3048 -0.1016)
			(end -0.3048 0.9906)
			(stroke
				(width 0.1)
				(type default)
			)
			(layer "F.Fab")
		)
		(pad "1" smd rect
			(at 0 0 180)
			(size 0.508 0.508)
			(layers "F.Cu" "F.Mask" "F.Paste")
			(net "VR_PVDDQ_DEF_AVSP")
		)
		(pad "2" smd rect
			(at 0 0.889 180)
			(size 0.508 0.508)
			(layers "F.Cu" "F.Mask" "F.Paste")
			(net "VSENSE_PVDDQ_DEF_N")
		)
		(zone
			(layer "F.Cu")
			(hatch none 0.5)
			(connect_pads
				(clearance 0)
			)
			(min_thickness 0.25)
			(keepout
				(tracks allowed)
				(vias not_allowed)
				(pads allowed)
				(copperpour not_allowed)
				(footprints allowed)
			)
			(placement
				(enabled no)
				(sheetname "")
			)
			(fill
				(thermal_gap 0.5)
				(thermal_bridge_width 0.5)
				(island_removal_mode 0)
			)
			(polygon
				(pts
					(xy 363.61624 -141.13637) (xy 364.12424 -141.13637) (xy 364.12424 -141.51737) (xy 363.61624 -141.51737)
				)
			)
		)
		(zone
			(layer "F.Cu")
			(hatch none 0.5)
			(connect_pads
				(clearance 0)
			)
			(min_thickness 0.25)
			(keepout
				(tracks not_allowed)
				(vias allowed)
				(pads allowed)
				(copperpour not_allowed)
				(footprints allowed)
			)
			(placement
				(enabled no)
				(sheetname "")
			)
			(fill
				(thermal_gap 0.5)
				(thermal_bridge_width 0.5)
				(island_removal_mode 0)
			)
			(polygon
				(pts
					(xy 363.61624 -141.13637) (xy 364.12424 -141.13637) (xy 364.12424 -141.51737) (xy 363.61624 -141.51737)
				)
			)
		)
	)
	(footprint ""
		(layer "F.Cu")
		(at 478.545144 -15.251938 -90)
		(property "Reference" "R9G20"
			(at -0.8382 -0.67818 270)
			(unlocked yes)
			(layer "F.SilkS")
			(effects
				(font
					(size 0.4064 0.254)
					(thickness 0.1524)
				)
				(justify left)
			)
		)
		(property "Value" ""
			(at 0 0 270)
			(layer "F.Fab")
			(effects
				(font
					(size 1.27 1.27)
				)
			)
		)
		(duplicate_pad_numbers_are_jumpers no)
		(fp_poly
			(pts
				(xy -0.2794 -0.1016) (xy 0.2794 -0.1016) (xy 0.2794 0.9906) (xy -0.2794 0.9906)
			)
			(stroke
				(width 0)
				(type default)
			)
			(fill no)
			(layer "F.CrtYd")
		)
		(fp_line
			(start -0.2794 0.9906)
			(end 0.2794 0.9906)
			(stroke
				(width 0.1)
				(type default)
			)
			(layer "F.Fab")
		)
		(fp_line
			(start 0.2794 0.9906)
			(end 0.2794 -0.1016)
			(stroke
				(width 0.1)
				(type default)
			)
			(layer "F.Fab")
		)
		(fp_line
			(start -0.2794 -0.1016)
			(end -0.2794 0.9906)
			(stroke
				(width 0.1)
				(type default)
			)
			(layer "F.Fab")
		)
		(fp_line
			(start 0.2794 -0.1016)
			(end -0.2794 -0.1016)
			(stroke
				(width 0.1)
				(type default)
			)
			(layer "F.Fab")
		)
		(pad "1" smd rect
			(at 0 0 270)
			(size 0.508 0.508)
			(layers "F.Cu" "F.Mask" "F.Paste")
			(net "NIC_MDI_SPRV_RJ45_1_DN")
		)
		(pad "2" smd rect
			(at 0 0.889 270)
			(size 0.508 0.508)
			(layers "F.Cu" "F.Mask" "F.Paste")
			(net "NIC_MDI_SPRV_RJ45_1_R_DN")
		)
		(zone
			(layer "F.Cu")
			(hatch none 0.5)
			(connect_pads
				(clearance 0)
			)
			(min_thickness 0.25)
			(keepout
				(tracks not_allowed)
				(vias allowed)
				(pads allowed)
				(copperpour not_allowed)
				(footprints allowed)
			)
			(placement
				(enabled no)
				(sheetname "")
			)
			(fill
				(thermal_gap 0.5)
				(thermal_bridge_width 0.5)
				(island_removal_mode 0)
			)
			(polygon
				(pts
					(xy 477.910144 -15.505938) (xy 477.910144 -14.997938) (xy 478.291144 -14.997938) (xy 478.291144 -15.505938)
				)
			)
		)
		(zone
			(layer "F.Cu")
			(hatch none 0.5)
			(connect_pads
				(clearance 0)
			)
			(min_thickness 0.25)
			(keepout
				(tracks allowed)
				(vias not_allowed)
				(pads allowed)
				(copperpour not_allowed)
				(footprints allowed)
			)
			(placement
				(enabled no)
				(sheetname "")
			)
			(fill
				(thermal_gap 0.5)
				(thermal_bridge_width 0.5)
				(island_removal_mode 0)
			)
			(polygon
				(pts
					(xy 478.291144 -15.505938) (xy 478.291144 -14.997938) (xy 477.910144 -14.997938) (xy 477.910144 -15.505938)
				)
			)
		)
	)
	(footprint ""
		(layer "F.Cu")
		(at 318.8716 -28.045918 -90)
		(property "Reference" "R6F11"
			(at 0 0 270)
			(layer "F.SilkS")
			(hide yes)
			(effects
				(font
					(size 1.27 1.27)
				)
			)
		)
		(property "Value" ""
			(at 0 0 270)
			(layer "F.Fab")
			(effects
				(font
					(size 1.27 1.27)
				)
			)
		)
		(duplicate_pad_numbers_are_jumpers no)
		(fp_poly
			(pts
				(xy -0.2794 -0.1016) (xy 0.2794 -0.1016) (xy 0.2794 0.9906) (xy -0.2794 0.9906)
			)
			(stroke
				(width 0)
				(type default)
			)
			(fill no)
			(layer "F.CrtYd")
		)
		(fp_line
			(start -0.2794 0.9906)
			(end 0.2794 0.9906)
			(stroke
				(width 0.1)
				(type default)
			)
			(layer "F.Fab")
		)
		(fp_line
			(start 0.2794 0.9906)
			(end 0.2794 -0.1016)
			(stroke
				(width 0.1)
				(type default)
			)
			(layer "F.Fab")
		)
		(fp_line
			(start -0.2794 -0.1016)
			(end -0.2794 0.9906)
			(stroke
				(width 0.1)
				(type default)
			)
			(layer "F.Fab")
		)
		(fp_line
			(start 0.2794 -0.1016)
			(end -0.2794 -0.1016)
			(stroke
				(width 0.1)
				(type default)
			)
			(layer "F.Fab")
		)
		(pad "1" smd rect
			(at 0 0 270)
			(size 0.508 0.508)
			(layers "F.Cu" "F.Mask" "F.Paste")
			(net "CLK_322M_156M_CPU0_OSC_VRM_DP")
		)
		(pad "2" smd rect
			(at 0 0.889 270)
			(size 0.508 0.508)
			(layers "F.Cu" "F.Mask" "F.Paste")
			(net "CLK_322M_OSC_CPU0_RC_DP")
		)
		(zone
			(layer "F.Cu")
			(hatch none 0.5)
			(connect_pads
				(clearance 0)
			)
			(min_thickness 0.25)
			(keepout
				(tracks not_allowed)
				(vias allowed)
				(pads allowed)
				(copperpour not_allowed)
				(footprints allowed)
			)
			(placement
				(enabled no)
				(sheetname "")
			)
			(fill
				(thermal_gap 0.5)
				(thermal_bridge_width 0.5)
				(island_removal_mode 0)
			)
			(polygon
				(pts
					(xy 318.2366 -28.299918) (xy 318.2366 -27.791918) (xy 318.6176 -27.791918) (xy 318.6176 -28.299918)
				)
			)
		)
		(zone
			(layer "F.Cu")
			(hatch none 0.5)
			(connect_pads
				(clearance 0)
			)
			(min_thickness 0.25)
			(keepout
				(tracks allowed)
				(vias not_allowed)
				(pads allowed)
				(copperpour not_allowed)
				(footprints allowed)
			)
			(placement
				(enabled no)
				(sheetname "")
			)
			(fill
				(thermal_gap 0.5)
				(thermal_bridge_width 0.5)
				(island_removal_mode 0)
			)
			(polygon
				(pts
					(xy 318.6176 -28.299918) (xy 318.6176 -27.791918) (xy 318.2366 -27.791918) (xy 318.2366 -28.299918)
				)
			)
		)
	)
	(footprint ""
		(layer "F.Cu")
		(at 22.479 -32.258)
		(property "Reference" "CR1F4"
			(at -1.016 -1.24333 0)
			(unlocked yes)
			(layer "F.SilkS")
			(effects
				(font
					(size 0.7874 0.5842)
					(thickness 0.1524)
				)
				(justify left)
			)
		)
		(property "Value" ""
			(at 0 0 0)
			(layer "F.Fab")
			(effects
				(font
					(size 1.27 1.27)
				)
			)
		)
		(duplicate_pad_numbers_are_jumpers no)
		(fp_line
			(start -1.8161 1.664462)
			(end -1.335278 0.831596)
			(stroke
				(width 0.1524)
				(type default)
			)
			(layer "F.SilkS")
		)
		(fp_line
			(start -1.335278 -0.291846)
			(end -1.335278 0.831596)
			(stroke
				(width 0.1524)
				(type default)
			)
			(layer "F.SilkS")
		)
		(fp_line
			(start -1.335278 0.831596)
			(end -0.854456 1.664462)
			(stroke
				(width 0.1524)
				(type default)
			)
			(layer "F.SilkS")
		)
		(fp_line
			(start -1.335278 1.664462)
			(end -1.8161 1.664462)
			(stroke
				(width 0.1524)
				(type default)
			)
			(layer "F.SilkS")
		)
		(fp_line
			(start -1.335278 2.576068)
			(end -1.335278 1.664462)
			(stroke
				(width 0.1524)
				(type default)
			)
			(layer "F.SilkS")
		)
		(fp_line
			(start -0.854456 0.831596)
			(end -1.8161 0.831596)
			(stroke
				(width 0.1524)
				(type default)
			)
			(layer "F.SilkS")
		)
		(fp_line
			(start -0.854456 1.664462)
			(end -1.335278 1.664462)
			(stroke
				(width 0.1524)
				(type default)
			)
			(layer "F.SilkS")
		)
		(fp_rect
			(start -0.67437 2.04216)
			(end 0.67437 0.24384)
			(stroke
				(width 0)
				(type default)
			)
			(fill no)
			(layer "F.CrtYd")
		)
		(fp_line
			(start -1.8161 1.664462)
			(end -1.335278 0.831596)
			(stroke
				(width 0.1)
				(type default)
			)
			(layer "F.Fab")
		)
		(fp_line
			(start -1.335278 0.831596)
			(end -1.335278 -0.291846)
			(stroke
				(width 0.1)
				(type default)
			)
			(layer "F.Fab")
		)
		(fp_line
			(start -1.335278 0.831596)
			(end -0.854456 1.664462)
			(stroke
				(width 0.1)
				(type default)
			)
			(layer "F.Fab")
		)
		(fp_line
			(start -1.335278 1.664462)
			(end -1.335278 2.576068)
			(stroke
				(width 0.1)
				(type default)
			)
			(layer "F.Fab")
		)
		(fp_line
			(start -0.854456 0.831596)
			(end -1.8161 0.831596)
			(stroke
				(width 0.1)
				(type default)
			)
			(layer "F.Fab")
		)
		(fp_line
			(start -0.854456 1.664462)
			(end -1.8161 1.664462)
			(stroke
				(width 0.1)
				(type default)
			)
			(layer "F.Fab")
		)
		(fp_line
			(start -0.67437 0.24384)
			(end -0.67437 2.04216)
			(stroke
				(width 0.1)
				(type default)
			)
			(layer "F.Fab")
		)
		(fp_line
			(start -0.67437 2.04216)
			(end 0.67437 2.04216)
			(stroke
				(width 0.1)
				(type default)
			)
			(layer "F.Fab")
		)
		(fp_line
			(start 0.67437 0.24384)
			(end -0.67437 0.24384)
			(stroke
				(width 0.1)
				(type default)
			)
			(layer "F.Fab")
		)
		(fp_line
			(start 0.67437 2.04216)
			(end 0.67437 0.24384)
			(stroke
				(width 0.1)
				(type default)
			)
			(layer "F.Fab")
		)
		(pad "1" smd rect
			(at 0 0)
			(size 0.4064 1.016)
			(layers "F.Cu" "F.Mask" "F.Paste")
			(net "FM_MATED_IN_D1_N")
		)
		(pad "2" smd rect
			(at 0 2.286)
			(size 0.4064 1.016)
			(layers "F.Cu" "F.Mask" "F.Paste")
			(net "FM_MATED_IN_N")
		)
	)
	(footprint ""
		(layer "F.Cu")
		(at 104.5591 -140.208 90)
		(property "Reference" "C2A15"
			(at 1.848866 0.752348 90)
			(unlocked yes)
			(layer "F.SilkS")
			(effects
				(font
					(size 1.27 0.9652)
					(thickness 0.1524)
				)
			)
		)
		(property "Value" ""
			(at 0 0 90)
			(layer "F.Fab")
			(effects
				(font
					(size 1.27 1.27)
				)
			)
		)
		(duplicate_pad_numbers_are_jumpers no)
		(fp_rect
			(start -0.500126 1.598422)
			(end 0.500126 -0.201422)
			(stroke
				(width 0)
				(type default)
			)
			(fill no)
			(layer "F.CrtYd")
		)
		(fp_line
			(start 0.500126 -0.201422)
			(end 0.500126 1.598422)
			(stroke
				(width 0.1)
				(type default)
			)
			(layer "F.Fab")
		)
		(fp_line
			(start -0.500126 -0.201422)
			(end 0.500126 -0.201422)
			(stroke
				(width 0.1)
				(type default)
			)
			(layer "F.Fab")
		)
		(fp_line
			(start 0.500126 1.598422)
			(end -0.500126 1.598422)
			(stroke
				(width 0.1)
				(type default)
			)
			(layer "F.Fab")
		)
		(fp_line
			(start -0.500126 1.598422)
			(end -0.500126 -0.201422)
			(stroke
				(width 0.1)
				(type default)
			)
			(layer "F.Fab")
		)
		(pad "1" smd rect
			(at 0 0)
			(size 0.889 0.9906)
			(layers "F.Cu" "F.Mask" "F.Paste")
			(net "PVDDQ_KLM")
		)
		(pad "2" smd rect
			(at 0 1.397)
			(size 0.889 0.9906)
			(layers "F.Cu" "F.Mask" "F.Paste")
			(net "GND")
		)
		(zone
			(layer "F.Cu")
			(hatch none 0.5)
			(connect_pads
				(clearance 0)
			)
			(min_thickness 0.25)
			(keepout
				(tracks not_allowed)
				(vias allowed)
				(pads allowed)
				(copperpour not_allowed)
				(footprints allowed)
			)
			(placement
				(enabled no)
				(sheetname "")
			)
			(fill
				(thermal_gap 0.5)
				(thermal_bridge_width 0.5)
				(island_removal_mode 0)
			)
			(polygon
				(pts
					(xy 105.5116 -139.7127) (xy 105.5116 -140.7033) (xy 105.0036 -140.7033) (xy 105.0036 -139.7127)
				)
			)
		)
		(zone
			(layer "F.Cu")
			(hatch none 0.5)
			(connect_pads
				(clearance 0)
			)
			(min_thickness 0.25)
			(keepout
				(tracks allowed)
				(vias not_allowed)
				(pads allowed)
				(copperpour not_allowed)
				(footprints allowed)
			)
			(placement
				(enabled no)
				(sheetname "")
			)
			(fill
				(thermal_gap 0.5)
				(thermal_bridge_width 0.5)
				(island_removal_mode 0)
			)
			(polygon
				(pts
					(xy 105.5116 -139.7127) (xy 105.5116 -140.7033) (xy 105.0036 -140.7033) (xy 105.0036 -139.7127)
				)
			)
		)
	)
)
